# T6G (Grand Teton) — schematic netlist excerpt (pin names and nets, part order shuffled) for the footprints in the layout excerpt that follows; sources: Cadence DE-HDL packaged netlist, KiCad conversion of 04192023_DAF0TMB3IC0_F0TG_MB_C_brd_V02_OCP.brd

R6095  Q_RES  0 5% CHIP  pkg 0402LF  page 80 : A = IRQ_HSC_FAULT_BUF_R_N ; B = IRQ_HSC_FAULT_BUF_N
C2439  Q_CAP  22UF 4V 20% X6S  pkg C0402  page 74 : A = PVDDCR_SOC_P1 ; B = GND

(kicad_pcb
	(version 20260206)
	(generator "pcbnew")
	(generator_version "10.0")
	(general
		(thickness 1.6)
		(legacy_teardrops no)
	)
	(paper "A4")
	(title_block
		(title "04192023_DAF0TMB3IC0_F0TG_MB_C_brd_V02_OCP.brd")
		(comment 1 "Grand Teton / footprints 1969-1970 of 8354")
	)
	(layers
		(0 "F.Cu" signal "TOP")
		(4 "In1.Cu" signal "GND")
		(6 "In2.Cu" signal "IN1")
		(8 "In3.Cu" signal "GND1")
		(10 "In4.Cu" signal "IN2")
		(12 "In5.Cu" signal "GND2")
		(14 "In6.Cu" signal "IN3")
		(16 "In7.Cu" signal "GND3")
		(18 "In8.Cu" signal "VCC")
		(20 "In9.Cu" signal "VCC1")
		(22 "In10.Cu" signal "GND4")
		(24 "In11.Cu" signal "IN4")
		(26 "In12.Cu" signal "GND5")
		(28 "In13.Cu" signal "IN5")
		(30 "In14.Cu" signal "GND6")
		(32 "In15.Cu" signal "IN6")
		(34 "In16.Cu" signal "GND7")
		(2 "B.Cu" signal "BOTTOM")
		(9 "F.Adhes" user "F.Adhesive")
		(11 "B.Adhes" user "B.Adhesive")
		(13 "F.Paste" user "Package Geometry/Pastemask Top")
		(15 "B.Paste" user "Package Geometry/Pastemask Bottom")
		(5 "F.SilkS" user "Ref Des/Silkscreen Top")
		(7 "B.SilkS" user "Ref Des/Silkscreen Bottom")
		(1 "F.Mask" user "Board Geometry/Soldermask Top")
		(3 "B.Mask" user "Board Geometry/Soldermask Bottom")
		(17 "Dwgs.User" user "User.Drawings")
		(19 "Cmts.User" user "User.Comments")
		(21 "Eco1.User" user "User.Eco1")
		(23 "Eco2.User" user "User.Eco2")
		(25 "Edge.Cuts" user "Board Geometry/Outline")
		(27 "Margin" user)
		(31 "F.CrtYd" user "Package Geometry/Place Bound Top")
		(29 "B.CrtYd" user "Package Geometry/Place Bound Bottom")
		(35 "F.Fab" user "Ref Des/Assembly Top")
		(33 "B.Fab" user "Ref Des/Assembly Bottom")
	)
	(footprint ""
		(layer "F.Cu")
		(at 113.375948 -256.012442 90)
		(property "Reference" "C2439"
			(at 0 0 90)
			(layer "F.SilkS")
			(hide yes)
			(effects
				(font
					(size 1.27 1.27)
				)
			)
		)
		(property "Value" ""
			(at 0 0 90)
			(layer "F.Fab")
			(effects
				(font
					(size 1.27 1.27)
				)
			)
		)
		(duplicate_pad_numbers_are_jumpers no)
		(fp_line
			(start 0.7874 -0.4064)
			(end 0.7874 0.4064)
			(stroke
				(width 0.1524)
				(type default)
			)
			(layer "F.SilkS")
		)
		(fp_line
			(start -0.7874 -0.4064)
			(end 0.7874 -0.4064)
			(stroke
				(width 0.1524)
				(type default)
			)
			(layer "F.SilkS")
		)
		(fp_line
			(start 0.7874 0.4064)
			(end -0.7874 0.4064)
			(stroke
				(width 0.1524)
				(type default)
			)
			(layer "F.SilkS")
		)
		(fp_line
			(start -0.7874 0.4064)
			(end -0.7874 -0.4064)
			(stroke
				(width 0.1524)
				(type default)
			)
			(layer "F.SilkS")
		)
		(fp_line
			(start -0.12065 -0.305054)
			(end -0.12065 -0.2794)
			(stroke
				(width 0.1)
				(type default)
			)
			(layer "F.Fab")
		)
		(fp_line
			(start -0.67945 -0.305054)
			(end -0.12065 -0.305054)
			(stroke
				(width 0.1)
				(type default)
			)
			(layer "F.Fab")
		)
		(fp_line
			(start 0.67945 -0.3048)
			(end 0.67945 0.3048)
			(stroke
				(width 0.1)
				(type default)
			)
			(layer "F.Fab")
		)
		(fp_line
			(start 0.12065 -0.3048)
			(end 0.67945 -0.3048)
			(stroke
				(width 0.1)
				(type default)
			)
			(layer "F.Fab")
		)
		(fp_line
			(start 0.12065 -0.2794)
			(end 0.12065 -0.3048)
			(stroke
				(width 0.1)
				(type default)
			)
			(layer "F.Fab")
		)
		(fp_line
			(start -0.12065 -0.2794)
			(end 0.12065 -0.2794)
			(stroke
				(width 0.1)
				(type default)
			)
			(layer "F.Fab")
		)
		(fp_line
			(start 0.120396 0.2794)
			(end -0.12065 0.2794)
			(stroke
				(width 0.1)
				(type default)
			)
			(layer "F.Fab")
		)
		(fp_line
			(start -0.12065 0.2794)
			(end -0.12065 0.3048)
			(stroke
				(width 0.1)
				(type default)
			)
			(layer "F.Fab")
		)
		(fp_line
			(start 0.67945 0.3048)
			(end 0.120396 0.3048)
			(stroke
				(width 0.1)
				(type default)
			)
			(layer "F.Fab")
		)
		(fp_line
			(start 0.120396 0.3048)
			(end 0.120396 0.2794)
			(stroke
				(width 0.1)
				(type default)
			)
			(layer "F.Fab")
		)
		(fp_line
			(start -0.12065 0.3048)
			(end -0.67945 0.3048)
			(stroke
				(width 0.1)
				(type default)
			)
			(layer "F.Fab")
		)
		(fp_line
			(start -0.67945 0.3048)
			(end -0.67945 -0.305054)
			(stroke
				(width 0.1)
				(type default)
			)
			(layer "F.Fab")
		)
		(pad "1" smd circle
			(at -0.40005 0 90)
			(size 0 0)
			(layers "F.Cu" "F.Mask" "F.Paste")
			(net "PVDDCR_SOC_P1")
		)
		(pad "2" smd circle
			(at 0.40005 0 90)
			(size 0 0)
			(layers "F.Cu" "F.Mask" "F.Paste")
			(net "GND")
		)
	)
	(footprint ""
		(layer "F.Cu")
		(at 171.196 -110.200948 180)
		(property "Reference" "R6095"
			(at 0 0 180)
			(layer "F.SilkS")
			(hide yes)
			(effects
				(font
					(size 1.27 1.27)
				)
			)
		)
		(property "Value" ""
			(at 0 0 180)
			(layer "F.Fab")
			(effects
				(font
					(size 1.27 1.27)
				)
			)
		)
		(duplicate_pad_numbers_are_jumpers no)
		(fp_line
			(start 0.7874 0.4064)
			(end -0.7874 0.4064)
			(stroke
				(width 0.1524)
				(type default)
			)
			(layer "F.SilkS")
		)
		(fp_line
			(start 0.7874 -0.4064)
			(end 0.7874 0.4064)
			(stroke
				(width 0.1524)
				(type default)
			)
			(layer "F.SilkS")
		)
		(fp_line
			(start -0.7874 0.4064)
			(end -0.7874 -0.4064)
			(stroke
				(width 0.1524)
				(type default)
			)
			(layer "F.SilkS")
		)
		(fp_line
			(start -0.7874 -0.4064)
			(end 0.7874 -0.4064)
			(stroke
				(width 0.1524)
				(type default)
			)
			(layer "F.SilkS")
		)
		(fp_line
			(start 0.67945 0.3048)
			(end 0.120396 0.3048)
			(stroke
				(width 0.1)
				(type default)
			)
			(layer "F.Fab")
		)
		(fp_line
			(start 0.67945 -0.3048)
			(end 0.67945 0.3048)
			(stroke
				(width 0.1)
				(type default)
			)
			(layer "F.Fab")
		)
		(fp_line
			(start 0.12065 -0.2794)
			(end 0.12065 -0.3048)
			(stroke
				(width 0.1)
				(type default)
			)
			(layer "F.Fab")
		)
		(fp_line
			(start 0.12065 -0.3048)
			(end 0.67945 -0.3048)
			(stroke
				(width 0.1)
				(type default)
			)
			(layer "F.Fab")
		)
		(fp_line
			(start 0.120396 0.3048)
			(end 0.120396 0.2794)
			(stroke
				(width 0.1)
				(type default)
			)
			(layer "F.Fab")
		)
		(fp_line
			(start 0.120396 0.2794)
			(end -0.12065 0.2794)
			(stroke
				(width 0.1)
				(type default)
			)
			(layer "F.Fab")
		)
		(fp_line
			(start -0.12065 0.3048)
			(end -0.67945 0.3048)
			(stroke
				(width 0.1)
				(type default)
			)
			(layer "F.Fab")
		)
		(fp_line
			(start -0.12065 0.2794)
			(end -0.12065 0.3048)
			(stroke
				(width 0.1)
				(type default)
			)
			(layer "F.Fab")
		)
		(fp_line
			(start -0.12065 -0.2794)
			(end 0.12065 -0.2794)
			(stroke
				(width 0.1)
				(type default)
			)
			(layer "F.Fab")
		)
		(fp_line
			(start -0.12065 -0.305054)
			(end -0.12065 -0.2794)
			(stroke
				(width 0.1)
				(type default)
			)
			(layer "F.Fab")
		)
		(fp_line
			(start -0.67945 0.3048)
			(end -0.67945 -0.305054)
			(stroke
				(width 0.1)
				(type default)
			)
			(layer "F.Fab")
		)
		(fp_line
			(start -0.67945 -0.305054)
			(end -0.12065 -0.305054)
			(stroke
				(width 0.1)
				(type default)
			)
			(layer "F.Fab")
		)
		(pad "1" smd circle
			(at -0.40005 0 180)
			(size 0 0)
			(layers "F.Cu" "F.Mask" "F.Paste")
			(net "IRQ_HSC_FAULT_BUF_R_N")
		)
		(pad "2" smd circle
			(at 0.40005 0 180)
			(size 0 0)
			(layers "F.Cu" "F.Mask" "F.Paste")
			(net "IRQ_HSC_FAULT_BUF_N")
		)
	)
)
